(kicad_pcb
	(version 20241229)
	(generator "pcbnew")
	(generator_version "9.0")
	(general
		(thickness 1.61)
		(legacy_teardrops no)
	)
	(paper "A3")
	(title_block
		(title "SO-DIMM DDR5 Tester")
		(date "2025-11-26")
		(rev "1.3.0")
		(comment 9 "footprints 443-448 of 627")
	)
	(layers
		(0 "F.Cu" signal)
		(4 "In1.Cu" power)
		(6 "In2.Cu" mixed)
		(8 "In3.Cu" power)
		(10 "In4.Cu" mixed)
		(12 "In5.Cu" power)
		(14 "In6.Cu" mixed)
		(16 "In7.Cu" power)
		(18 "In8.Cu" power)
		(20 "In9.Cu" mixed)
		(22 "In10.Cu" power)
		(2 "B.Cu" signal)
		(9 "F.Adhes" user "F.Adhesive")
		(11 "B.Adhes" user "B.Adhesive")
		(13 "F.Paste" user)
		(15 "B.Paste" user)
		(5 "F.SilkS" user "F.Silkscreen")
		(7 "B.SilkS" user "B.Silkscreen")
		(1 "F.Mask" user)
		(3 "B.Mask" user)
		(17 "Dwgs.User" user "User.Drawings")
		(19 "Cmts.User" user "User.Comments")
		(21 "Eco1.User" user "User.Eco1")
		(23 "Eco2.User" user "User.Eco2")
		(25 "Edge.Cuts" user)
		(27 "Margin" user)
		(31 "F.CrtYd" user "F.Courtyard")
		(29 "B.CrtYd" user "B.Courtyard")
		(35 "F.Fab" user)
		(33 "B.Fab" user)
	)
	(footprint "antmicro-footprints:R_0402_1005Metric"
		(layer "B.Cu")
		(at 84.273 130.7 180)
		(descr "Resistor SMD 0402")
		(tags "resistor SMD 0402")
		(property "Reference" "R193"
			(at -1.122484 0.772697 0)
			(layer "B.SilkS")
			(hide yes)
			(effects
				(font
					(size 0.7 0.7)
					(thickness 0.15)
				)
				(justify left bottom mirror)
			)
		)
		(property "Value" "R_330R_0402"
			(at -1.011843 -1.772047 0)
			(layer "B.Fab")
			(effects
				(font
					(size 0.7 0.7)
					(thickness 0.15)
				)
				(justify left bottom mirror)
			)
		)
		(property "Datasheet" "https://www.bourns.com/docs/product-datasheets/cr.pdf"
			(at 0 0 180)
			(layer "F.Fab")
			(hide yes)
			(effects
				(font
					(size 1.27 1.27)
					(thickness 0.15)
				)
			)
		)
		(property "Author" "Antmicro"
			(at 168.546 261.4 0)
			(layer "B.Fab")
			(hide yes)
			(effects
				(font
					(size 1 1)
					(thickness 0.15)
				)
				(justify mirror)
			)
		)
		(property "License" "Apache-2.0"
			(at 168.546 261.4 0)
			(layer "B.Fab")
			(hide yes)
			(effects
				(font
					(size 1 1)
					(thickness 0.15)
				)
				(justify mirror)
			)
		)
		(property "MPN" "CR0402-FX-3300GLF"
			(at 168.546 261.4 0)
			(layer "B.Fab")
			(hide yes)
			(effects
				(font
					(size 1 1)
					(thickness 0.15)
				)
				(justify mirror)
			)
		)
		(property "Manufacturer" "Bourns"
			(at 168.546 261.4 0)
			(layer "B.Fab")
			(hide yes)
			(effects
				(font
					(size 1 1)
					(thickness 0.15)
				)
				(justify mirror)
			)
		)
		(property "Tolerance" "1%"
			(at 168.546 261.4 0)
			(layer "B.Fab")
			(hide yes)
			(effects
				(font
					(size 1 1)
					(thickness 0.15)
				)
				(justify mirror)
			)
		)
		(property "Val" "330R"
			(at 168.546 261.4 0)
			(layer "B.Fab")
			(hide yes)
			(effects
				(font
					(size 1 1)
					(thickness 0.15)
				)
				(justify mirror)
			)
		)
		(sheetname "/Ethernet/")
		(sheetfile "ethernet.kicad_sch")
		(attr smd)
		(fp_rect
			(start -0.93 0.47)
			(end 0.93 -0.47)
			(stroke
				(width 0.05)
				(type solid)
			)
			(fill no)
			(layer "B.CrtYd")
		)
		(fp_rect
			(start -0.5 0.25)
			(end 0.5 -0.25)
			(stroke
				(width 0.15)
				(type solid)
			)
			(fill no)
			(layer "B.Fab")
		)
		(pad "1" smd roundrect
			(at -0.485 0 180)
			(size 0.59 0.64)
			(layers "B.Cu" "B.Mask" "B.Paste")
			(roundrect_rratio 0.25)
			(net 1 "GND")
			(pintype "passive")
		)
		(pad "2" smd roundrect
			(at 0.485 0 180)
			(size 0.59 0.64)
			(layers "B.Cu" "B.Mask" "B.Paste")
			(roundrect_rratio 0.25)
			(net 32 "Net-(C234-Pad1)")
			(pintype "passive")
		)
	)
	(footprint "antmicro-footprints:C_0402_1005Metric"
		(layer "B.Cu")
		(at 151 142.4 -90)
		(descr "Capacitor SMD 0402")
		(tags "capacitor SMD 0402")
		(property "Reference" "C8"
			(at 0 0.699 90)
			(layer "B.SilkS")
			(hide yes)
			(effects
				(font
					(size 0.7 0.7)
					(thickness 0.15)
				)
				(justify left bottom mirror)
			)
		)
		(property "Value" "C_100n_0402"
			(at -1.022927 -2.155213 90)
			(layer "B.Fab")
			(effects
				(font
					(size 0.7 0.7)
					(thickness 0.15)
				)
				(justify left bottom mirror)
			)
		)
		(property "Datasheet" "https://www.murata.com/products/productdetail?partno=GRM155R61H104KE14%23"
			(at 0 0 270)
			(layer "F.Fab")
			(hide yes)
			(effects
				(font
					(size 1.27 1.27)
					(thickness 0.15)
				)
			)
		)
		(property "Author" "Antmicro"
			(at 8.6 293.4 0)
			(layer "B.Fab")
			(hide yes)
			(effects
				(font
					(size 1 1)
					(thickness 0.15)
				)
				(justify mirror)
			)
		)
		(property "Dielectric" "X5R"
			(at 8.6 293.4 0)
			(layer "B.Fab")
			(hide yes)
			(effects
				(font
					(size 1 1)
					(thickness 0.15)
				)
				(justify mirror)
			)
		)
		(property "License" "Apache-2.0"
			(at 8.6 293.4 0)
			(layer "B.Fab")
			(hide yes)
			(effects
				(font
					(size 1 1)
					(thickness 0.15)
				)
				(justify mirror)
			)
		)
		(property "MPN" "GRM155R61H104KE14D"
			(at 8.6 293.4 0)
			(layer "B.Fab")
			(hide yes)
			(effects
				(font
					(size 1 1)
					(thickness 0.15)
				)
				(justify mirror)
			)
		)
		(property "Manufacturer" "Murata"
			(at 8.6 293.4 0)
			(layer "B.Fab")
			(hide yes)
			(effects
				(font
					(size 1 1)
					(thickness 0.15)
				)
				(justify mirror)
			)
		)
		(property "Val" "100n"
			(at 8.6 293.4 0)
			(layer "B.Fab")
			(hide yes)
			(effects
				(font
					(size 1 1)
					(thickness 0.15)
				)
				(justify mirror)
			)
		)
		(property "Voltage" "50V"
			(at 8.6 293.4 0)
			(layer "B.Fab")
			(hide yes)
			(effects
				(font
					(size 1 1)
					(thickness 0.15)
				)
				(justify mirror)
			)
		)
		(sheetname "/DDR5 SODIMM/")
		(sheetfile "ddr5-sodimm.kicad_sch")
		(attr smd)
		(fp_rect
			(start -0.9659 0.481258)
			(end 0.9649 -0.458742)
			(stroke
				(width 0.05)
				(type solid)
			)
			(fill no)
			(layer "B.CrtYd")
		)
		(fp_line
			(start -0.499 0.25)
			(end 0.499 0.25)
			(stroke
				(width 0.15)
				(type solid)
			)
			(layer "B.Fab")
		)
		(fp_line
			(start 0.499 0.25)
			(end 0.499 -0.248)
			(stroke
				(width 0.15)
				(type solid)
			)
			(layer "B.Fab")
		)
		(fp_line
			(start -0.499 -0.248)
			(end -0.499 0.25)
			(stroke
				(width 0.15)
				(type solid)
			)
			(layer "B.Fab")
		)
		(fp_line
			(start 0.499 -0.248)
			(end -0.499 -0.248)
			(stroke
				(width 0.15)
				(type solid)
			)
			(layer "B.Fab")
		)
		(pad "1" smd roundrect
			(at -0.484 0 270)
			(size 0.59 0.64)
			(layers "B.Cu" "B.Mask" "B.Paste")
			(roundrect_rratio 0.25)
			(net 1 "GND")
			(pintype "passive")
		)
		(pad "2" smd roundrect
			(at 0.484 0 270)
			(size 0.59 0.64)
			(layers "B.Cu" "B.Mask" "B.Paste")
			(roundrect_rratio 0.25)
			(net 206 "+1V1")
			(pintype "passive")
		)
	)
	(footprint "antmicro-footprints:R_0402_1005Metric"
		(layer "B.Cu")
		(at 195.415 145.851)
		(descr "Resistor SMD 0402")
		(tags "resistor SMD 0402")
		(property "Reference" "R190"
			(at -1.122484 0.772697 180)
			(layer "B.SilkS")
			(hide yes)
			(effects
				(font
					(size 0.7 0.7)
					(thickness 0.15)
				)
				(justify left bottom mirror)
			)
		)
		(property "Value" "R_47k_0402"
			(at -1.011843 -1.772047 180)
			(layer "B.Fab")
			(effects
				(font
					(size 0.7 0.7)
					(thickness 0.15)
				)
				(justify left bottom mirror)
			)
		)
		(property "Datasheet" "https://www.bourns.com/docs/product-datasheets/cr.pdf"
			(at 0 0 0)
			(layer "F.Fab")
			(hide yes)
			(effects
				(font
					(size 1.27 1.27)
					(thickness 0.15)
				)
			)
		)
		(property "Author" "Antmicro"
			(at 0 0 0)
			(layer "B.Fab")
			(hide yes)
			(effects
				(font
					(size 1 1)
					(thickness 0.15)
				)
				(justify mirror)
			)
		)
		(property "License" "Apache-2.0"
			(at 0 0 0)
			(layer "B.Fab")
			(hide yes)
			(effects
				(font
					(size 1 1)
					(thickness 0.15)
				)
				(justify mirror)
			)
		)
		(property "MPN" "CR0402-FX-4702GLF"
			(at 0 0 0)
			(layer "B.Fab")
			(hide yes)
			(effects
				(font
					(size 1 1)
					(thickness 0.15)
				)
				(justify mirror)
			)
		)
		(property "Manufacturer" "Bourns"
			(at 0 0 0)
			(layer "B.Fab")
			(hide yes)
			(effects
				(font
					(size 1 1)
					(thickness 0.15)
				)
				(justify mirror)
			)
		)
		(property "Tolerance" "1%"
			(at 0 0 0)
			(layer "B.Fab")
			(hide yes)
			(effects
				(font
					(size 1 1)
					(thickness 0.15)
				)
				(justify mirror)
			)
		)
		(property "Val" "47k"
			(at 0 0 0)
			(layer "B.Fab")
			(hide yes)
			(effects
				(font
					(size 1 1)
					(thickness 0.15)
				)
				(justify mirror)
			)
		)
		(sheetname "/Supply/")
		(sheetfile "supply.kicad_sch")
		(attr smd)
		(fp_rect
			(start -0.93 0.47)
			(end 0.93 -0.47)
			(stroke
				(width 0.05)
				(type solid)
			)
			(fill no)
			(layer "B.CrtYd")
		)
		(fp_rect
			(start -0.5 0.25)
			(end 0.5 -0.25)
			(stroke
				(width 0.15)
				(type solid)
			)
			(fill no)
			(layer "B.Fab")
		)
		(pad "1" smd roundrect
			(at -0.485 0)
			(size 0.59 0.64)
			(layers "B.Cu" "B.Mask" "B.Paste")
			(roundrect_rratio 0.25)
			(net 223 "/Supply/EN3")
			(pintype "passive")
		)
		(pad "2" smd roundrect
			(at 0.485 0)
			(size 0.59 0.64)
			(layers "B.Cu" "B.Mask" "B.Paste")
			(roundrect_rratio 0.25)
			(net 41 "+3V3_AON")
			(pintype "passive")
		)
	)
	(footprint "antmicro-footprints:C_0402_1005Metric"
		(layer "B.Cu")
		(at 140.375501 164.801 90)
		(descr "Capacitor SMD 0402 (1005 Metric), square (rectangular) end terminal, IPC_7351 nominal, (Body size source: IPC-SM-782 page 76, https://www.pcb-3d.com/wordpress/wp-content/uploads/ipc-sm-782a_amendment_1_and_2.pdf)")
		(tags "capacitor 0402")
		(property "Reference" "C66"
			(at 0 1.17 270)
			(layer "B.SilkS")
			(hide yes)
			(effects
				(font
					(size 0.7 0.7)
					(thickness 0.15)
				)
				(justify left bottom mirror)
			)
		)
		(property "Value" "C_100n_0402"
			(at 0 -1.169 270)
			(layer "B.Fab")
			(effects
				(font
					(size 0.7 0.7)
					(thickness 0.15)
				)
				(justify left bottom mirror)
			)
		)
		(property "Datasheet" "https://www.murata.com/products/productdetail?partno=GRM155R61H104KE14%23"
			(at 0 0 90)
			(layer "F.Fab")
			(hide yes)
			(effects
				(font
					(size 1.27 1.27)
					(thickness 0.15)
				)
			)
		)
		(property "Author" "Antmicro"
			(at 305.176501 24.425499 0)
			(layer "B.Fab")
			(hide yes)
			(effects
				(font
					(size 1 1)
					(thickness 0.15)
				)
				(justify mirror)
			)
		)
		(property "Dielectric" "X5R"
			(at 305.176501 24.425499 0)
			(layer "B.Fab")
			(hide yes)
			(effects
				(font
					(size 1 1)
					(thickness 0.15)
				)
				(justify mirror)
			)
		)
		(property "License" "Apache-2.0"
			(at 305.176501 24.425499 0)
			(layer "B.Fab")
			(hide yes)
			(effects
				(font
					(size 1 1)
					(thickness 0.15)
				)
				(justify mirror)
			)
		)
		(property "MPN" "GRM155R61H104KE14D"
			(at 305.176501 24.425499 0)
			(layer "B.Fab")
			(hide yes)
			(effects
				(font
					(size 1 1)
					(thickness 0.15)
				)
				(justify mirror)
			)
		)
		(property "Manufacturer" "Murata"
			(at 305.176501 24.425499 0)
			(layer "B.Fab")
			(hide yes)
			(effects
				(font
					(size 1 1)
					(thickness 0.15)
				)
				(justify mirror)
			)
		)
		(property "Val" "100n"
			(at 305.176501 24.425499 0)
			(layer "B.Fab")
			(hide yes)
			(effects
				(font
					(size 1 1)
					(thickness 0.15)
				)
				(justify mirror)
			)
		)
		(property "Voltage" "50V"
			(at 305.176501 24.425499 0)
			(layer "B.Fab")
			(hide yes)
			(effects
				(font
					(size 1 1)
					(thickness 0.15)
				)
				(justify mirror)
			)
		)
		(sheetname "/FPGA power/")
		(sheetfile "fpga-power.kicad_sch")
		(attr smd)
		(fp_rect
			(start -0.9656 0.4572)
			(end 0.9652 -0.4828)
			(stroke
				(width 0.05)
				(type solid)
			)
			(fill no)
			(layer "B.CrtYd")
		)
		(fp_line
			(start 0.498 -0.248)
			(end -0.5 -0.248)
			(stroke
				(width 0.15)
				(type solid)
			)
			(layer "B.Fab")
		)
		(fp_line
			(start -0.5 -0.248)
			(end -0.5 0.25)
			(stroke
				(width 0.15)
				(type solid)
			)
			(layer "B.Fab")
		)
		(fp_line
			(start 0.498 0.25)
			(end 0.498 -0.248)
			(stroke
				(width 0.15)
				(type solid)
			)
			(layer "B.Fab")
		)
		(fp_line
			(start -0.5 0.25)
			(end 0.498 0.25)
			(stroke
				(width 0.15)
				(type solid)
			)
			(layer "B.Fab")
		)
		(pad "1" smd roundrect
			(at -0.5 0)
			(size 0.6 0.6)
			(layers "B.Cu" "B.Mask" "B.Paste")
			(roundrect_rratio 0.25)
			(net 1 "GND")
			(pintype "passive")
		)
		(pad "2" smd roundrect
			(at 0.498 0 90)
			(size 0.6 0.6)
			(layers "B.Cu" "B.Mask" "B.Paste")
			(roundrect_rratio 0.25)
			(net 206 "+1V1")
			(pintype "passive")
		)
	)
	(footprint "antmicro-footprints:C_0402_1005Metric"
		(layer "B.Cu")
		(at 150.375501 169.8025 -90)
		(descr "Capacitor SMD 0402 (1005 Metric), square (rectangular) end terminal, IPC_7351 nominal, (Body size source: IPC-SM-782 page 76, https://www.pcb-3d.com/wordpress/wp-content/uploads/ipc-sm-782a_amendment_1_and_2.pdf)")
		(tags "capacitor 0402")
		(property "Reference" "C95"
			(at 0 1.17 90)
			(layer "B.SilkS")
			(hide yes)
			(effects
				(font
					(size 0.7 0.7)
					(thickness 0.15)
				)
				(justify left bottom mirror)
			)
		)
		(property "Value" "C_100n_0402"
			(at 0 -1.169 90)
			(layer "B.Fab")
			(effects
				(font
					(size 0.7 0.7)
					(thickness 0.15)
				)
				(justify left bottom mirror)
			)
		)
		(property "Datasheet" "https://www.murata.com/products/productdetail?partno=GRM155R61H104KE14%23"
			(at 0 0 270)
			(layer "F.Fab")
			(hide yes)
			(effects
				(font
					(size 1.27 1.27)
					(thickness 0.15)
				)
			)
		)
		(property "Author" "Antmicro"
			(at -19.426999 320.178001 0)
			(layer "B.Fab")
			(hide yes)
			(effects
				(font
					(size 1 1)
					(thickness 0.15)
				)
				(justify mirror)
			)
		)
		(property "Dielectric" "X5R"
			(at -19.426999 320.178001 0)
			(layer "B.Fab")
			(hide yes)
			(effects
				(font
					(size 1 1)
					(thickness 0.15)
				)
				(justify mirror)
			)
		)
		(property "License" "Apache-2.0"
			(at -19.426999 320.178001 0)
			(layer "B.Fab")
			(hide yes)
			(effects
				(font
					(size 1 1)
					(thickness 0.15)
				)
				(justify mirror)
			)
		)
		(property "MPN" "GRM155R61H104KE14D"
			(at -19.426999 320.178001 0)
			(layer "B.Fab")
			(hide yes)
			(effects
				(font
					(size 1 1)
					(thickness 0.15)
				)
				(justify mirror)
			)
		)
		(property "Manufacturer" "Murata"
			(at -19.426999 320.178001 0)
			(layer "B.Fab")
			(hide yes)
			(effects
				(font
					(size 1 1)
					(thickness 0.15)
				)
				(justify mirror)
			)
		)
		(property "Val" "100n"
			(at -19.426999 320.178001 0)
			(layer "B.Fab")
			(hide yes)
			(effects
				(font
					(size 1 1)
					(thickness 0.15)
				)
				(justify mirror)
			)
		)
		(property "Voltage" "50V"
			(at -19.426999 320.178001 0)
			(layer "B.Fab")
			(hide yes)
			(effects
				(font
					(size 1 1)
					(thickness 0.15)
				)
				(justify mirror)
			)
		)
		(sheetname "/FPGA power/")
		(sheetfile "fpga-power.kicad_sch")
		(attr smd)
		(fp_rect
			(start -0.9656 0.4572)
			(end 0.9652 -0.4828)
			(stroke
				(width 0.05)
				(type solid)
			)
			(fill no)
			(layer "B.CrtYd")
		)
		(fp_line
			(start -0.5 0.25)
			(end 0.498 0.25)
			(stroke
				(width 0.15)
				(type solid)
			)
			(layer "B.Fab")
		)
		(fp_line
			(start 0.498 0.25)
			(end 0.498 -0.248)
			(stroke
				(width 0.15)
				(type solid)
			)
			(layer "B.Fab")
		)
		(fp_line
			(start -0.5 -0.248)
			(end -0.5 0.25)
			(stroke
				(width 0.15)
				(type solid)
			)
			(layer "B.Fab")
		)
		(fp_line
			(start 0.498 -0.248)
			(end -0.5 -0.248)
			(stroke
				(width 0.15)
				(type solid)
			)
			(layer "B.Fab")
		)
		(pad "1" smd roundrect
			(at -0.5 0 180)
			(size 0.6 0.6)
			(layers "B.Cu" "B.Mask" "B.Paste")
			(roundrect_rratio 0.25)
			(net 1 "GND")
			(pintype "passive")
		)
		(pad "2" smd roundrect
			(at 0.498 0 270)
			(size 0.6 0.6)
			(layers "B.Cu" "B.Mask" "B.Paste")
			(roundrect_rratio 0.25)
			(net 206 "+1V1")
			(pintype "passive")
		)
	)
	(footprint "antmicro-footprints:C_0402_1005Metric"
		(layer "B.Cu")
		(at 144.877001 186.3005 180)
		(descr "Capacitor SMD 0402 (1005 Metric), square (rectangular) end terminal, IPC_7351 nominal, (Body size source: IPC-SM-782 page 76, https://www.pcb-3d.com/wordpress/wp-content/uploads/ipc-sm-782a_amendment_1_and_2.pdf)")
		(tags "capacitor 0402")
		(property "Reference" "C51"
			(at 0 1.17 0)
			(layer "B.SilkS")
			(hide yes)
			(effects
				(font
					(size 0.7 0.7)
					(thickness 0.15)
				)
				(justify left bottom mirror)
			)
		)
		(property "Value" "C_100n_0402"
			(at 0 -1.169 0)
			(layer "B.Fab")
			(effects
				(font
					(size 0.7 0.7)
					(thickness 0.15)
				)
				(justify left bottom mirror)
			)
		)
		(property "Datasheet" "https://www.murata.com/products/productdetail?partno=GRM155R61H104KE14%23"
			(at 0 0 180)
			(layer "F.Fab")
			(hide yes)
			(effects
				(font
					(size 1.27 1.27)
					(thickness 0.15)
				)
			)
		)
		(property "Author" "Antmicro"
			(at 289.754002 372.601 0)
			(layer "B.Fab")
			(hide yes)
			(effects
				(font
					(size 1 1)
					(thickness 0.15)
				)
				(justify mirror)
			)
		)
		(property "Dielectric" "X5R"
			(at 289.754002 372.601 0)
			(layer "B.Fab")
			(hide yes)
			(effects
				(font
					(size 1 1)
					(thickness 0.15)
				)
				(justify mirror)
			)
		)
		(property "License" "Apache-2.0"
			(at 289.754002 372.601 0)
			(layer "B.Fab")
			(hide yes)
			(effects
				(font
					(size 1 1)
					(thickness 0.15)
				)
				(justify mirror)
			)
		)
		(property "MPN" "GRM155R61H104KE14D"
			(at 289.754002 372.601 0)
			(layer "B.Fab")
			(hide yes)
			(effects
				(font
					(size 1 1)
					(thickness 0.15)
				)
				(justify mirror)
			)
		)
		(property "Manufacturer" "Murata"
			(at 289.754002 372.601 0)
			(layer "B.Fab")
			(hide yes)
			(effects
				(font
					(size 1 1)
					(thickness 0.15)
				)
				(justify mirror)
			)
		)
		(property "Val" "100n"
			(at 289.754002 372.601 0)
			(layer "B.Fab")
			(hide yes)
			(effects
				(font
					(size 1 1)
					(thickness 0.15)
				)
				(justify mirror)
			)
		)
		(property "Voltage" "50V"
			(at 289.754002 372.601 0)
			(layer "B.Fab")
			(hide yes)
			(effects
				(font
					(size 1 1)
					(thickness 0.15)
				)
				(justify mirror)
			)
		)
		(sheetname "/FPGA power/")
		(sheetfile "fpga-power.kicad_sch")
		(attr smd)
		(fp_rect
			(start -0.9656 0.4572)
			(end 0.9652 -0.4828)
			(stroke
				(width 0.05)
				(type solid)
			)
			(fill no)
			(layer "B.CrtYd")
		)
		(fp_line
			(start 0.498 0.25)
			(end 0.498 -0.248)
			(stroke
				(width 0.15)
				(type solid)
			)
			(layer "B.Fab")
		)
		(fp_line
			(start 0.498 -0.248)
			(end -0.5 -0.248)
			(stroke
				(width 0.15)
				(type solid)
			)
			(layer "B.Fab")
		)
		(fp_line
			(start -0.5 0.25)
			(end 0.498 0.25)
			(stroke
				(width 0.15)
				(type solid)
			)
			(layer "B.Fab")
		)
		(fp_line
			(start -0.5 -0.248)
			(end -0.5 0.25)
			(stroke
				(width 0.15)
				(type solid)
			)
			(layer "B.Fab")
		)
		(pad "1" smd roundrect
			(at -0.5 0 90)
			(size 0.6 0.6)
			(layers "B.Cu" "B.Mask" "B.Paste")
			(roundrect_rratio 0.25)
			(net 1 "GND")
			(pintype "passive")
		)
		(pad "2" smd roundrect
			(at 0.498 0 180)
			(size 0.6 0.6)
			(layers "B.Cu" "B.Mask" "B.Paste")
			(roundrect_rratio 0.25)
			(net 200 "+3V3")
			(pintype "passive")
		)
	)
)
